(kicad_pcb
	(version 20221018)
	(generator pcbnew)
	(general
    (thickness 0.908)
  )
	(paper "A4")
	(title_block
    (title "HDMI-MIPI Bridge")
    (date "2024-04-24")
    (rev "1.3.2")
		(comment 9 "footprints 34-41 of 121")
	)
	(layers
    (0 "F.Cu" signal)
    (1 "In1.Cu" signal)
    (2 "In2.Cu" signal)
    (31 "B.Cu" signal)
    (32 "B.Adhes" user "B.Adhesive")
    (33 "F.Adhes" user "F.Adhesive")
    (34 "B.Paste" user)
    (35 "F.Paste" user)
    (36 "B.SilkS" user "B.Silkscreen")
    (37 "F.SilkS" user "F.Silkscreen")
    (38 "B.Mask" user)
    (39 "F.Mask" user)
    (40 "Dwgs.User" user "User.Drawings")
    (41 "Cmts.User" user "User.Comments")
    (42 "Eco1.User" user "User.Eco1")
    (43 "Eco2.User" user "User.Eco2")
    (44 "Edge.Cuts" user)
    (45 "Margin" user)
    (46 "B.CrtYd" user "B.Courtyard")
    (47 "F.CrtYd" user "F.Courtyard")
    (48 "B.Fab" user)
    (49 "F.Fab" user)
  )
	(footprint "antmicro-footprints:SOT1069-2" (layer "F.Cu")
    (at 141.6 103.8)
    (property "Author" "Antmicro")
    (property "License" "Apache-2.0")
    (property "MPN" "PCA9517ATP")
    (property "Manufacturer" "NXP")
    (property "Sheetfile" "channel1.kicad_sch")
    (property "Sheetname" "Channel 1")
    (property "ki_description" "Level Translating I2C-Bus Repeater, 2 Inputs, 0.9 V to 5.5 V Supply, 50 mA Out, HWSON-8")
    (property "ki_keywords" "SMT, LEVEL-SHIFTER, IC, I2C")
    (attr smd)
    (fp_text reference "U3" (at 0.06 -2.33 180) (layer "F.SilkS")
        (effects (font (size 0.7 0.7) (thickness 0.15)) (justify left bottom))
    )
    (fp_text value "PCA9517ATP" (at -2.54 3.4544) (layer "F.Fab")
        (effects (font (size 0.7 0.7) (thickness 0.15)) (justify left bottom))
    )
    (fp_text user "." (at -3.101 -1.101 unlocked) (layer "F.SilkS") hide
        (effects (font (size 0.7 0.7) (thickness 0.15)) (justify left bottom))
    )
    (fp_text user "Author: Antmicro" (at -4.375 4.7) (layer "F.Fab") hide
        (effects (font (size 0.7 0.7) (thickness 0.15)) (justify left bottom))
    )
    (fp_text user "${REFERENCE}" (at -4.375 3.499) (layer "F.Fab") hide
        (effects (font (size 0.7 0.7) (thickness 0.15)) (justify left bottom))
    )
    (fp_text user "License: Apache-2.0" (at -4.375 5.9) (layer "F.Fab") hide
        (effects (font (size 0.7 0.7) (thickness 0.15)) (justify left bottom))
    )
    (fp_line (start -1.375 -2.226) (end 1.375 -2.226)
      (stroke (width 0.15) (type solid)) (layer "F.SilkS"))
    (fp_line (start -1.375 1.425) (end -1.375 -2.226)
      (stroke (width 0.15) (type solid)) (layer "F.SilkS"))
    (fp_line (start -0.577 2.224) (end -1.375 1.425)
      (stroke (width 0.15) (type solid)) (layer "F.SilkS"))
    (fp_line (start 1.375 -2.226) (end 1.375 2.224)
      (stroke (width 0.15) (type solid)) (layer "F.SilkS"))
    (fp_line (start 1.375 2.224) (end -0.577 2.224)
      (stroke (width 0.15) (type solid)) (layer "F.SilkS"))
    (fp_circle (center -1.3208 2.0836) (end -1.2708 2.0836)
      (stroke (width 0.15) (type solid)) (fill solid) (layer "F.SilkS"))
    (fp_line (start -1.13 -2) (end 1.12 -2)
      (stroke (width 0.05) (type solid)) (layer "F.CrtYd"))
    (fp_line (start -1.13 1.98) (end -1.13 -2)
      (stroke (width 0.05) (type solid)) (layer "F.CrtYd"))
    (fp_line (start 1.12 -2) (end 1.12 1.98)
      (stroke (width 0.05) (type solid)) (layer "F.CrtYd"))
    (fp_line (start 1.12 1.98) (end -1.13 1.98)
      (stroke (width 0.05) (type solid)) (layer "F.CrtYd"))
    (pad "1" smd rect (at -0.75 1.411) (size 0.25 0.625) (layers "F.Cu" "F.Paste" "F.Mask")
      (net 9 "+3V3") (pinfunction "Vref1") (pintype "power_in"))
    (pad "2" smd rect (at -0.25 1.411) (size 0.25 0.625) (layers "F.Cu" "F.Paste" "F.Mask")
      (net 105 "/Channel 1/HDMI1_DDC_SCL_3V3") (pinfunction "SCL1") (pintype "input"))
    (pad "3" smd rect (at 0.25 1.411) (size 0.25 0.625) (layers "F.Cu" "F.Paste" "F.Mask")
      (net 104 "/Channel 1/HDMI1_DDC_SDA_3V3") (pinfunction "SDA1") (pintype "bidirectional"))
    (pad "4" smd rect (at 0.75 1.411) (size 0.25 0.625) (layers "F.Cu" "F.Paste" "F.Mask")
      (net 2 "GND") (pinfunction "GND") (pintype "power_in"))
    (pad "5" smd rect (at 0.75 -1.414) (size 0.25 0.625) (layers "F.Cu" "F.Paste" "F.Mask")
      (net 118 "Net-(U3-EN)") (pinfunction "EN") (pintype "input"))
    (pad "6" smd rect (at 0.25 -1.414) (size 0.25 0.625) (layers "F.Cu" "F.Paste" "F.Mask")
      (net 85 "/Channel 1/HDMI1_DDC_SDA") (pinfunction "SDA2") (pintype "bidirectional"))
    (pad "7" smd rect (at -0.25 -1.414) (size 0.25 0.625) (layers "F.Cu" "F.Paste" "F.Mask")
      (net 84 "/Channel 1/HDMI1_DDC_SCL") (pinfunction "SCL2") (pintype "input"))
    (pad "8" smd rect (at -0.75 -1.414) (size 0.25 0.625) (layers "F.Cu" "F.Paste" "F.Mask")
      (net 14 "+5V") (pinfunction "Vref2") (pintype "power_in"))
    (pad "9" smd roundrect (at 0 0) (size 1.6 1.6) (layers "F.Cu" "F.Paste" "F.Mask") (roundrect_rratio 0.05)
      (net 2 "GND") (pinfunction "GND") (pintype "passive") (solder_paste_margin -0.05))
  )
	(footprint "antmicro-footprints:C_0402_1005Metric" (layer "F.Cu")
    (at 123 110.2 90)
    (descr "Capacitor SMD 0402")
    (tags "capacitor SMD 0402")
    (property "Author" "Antmicro")
    (property "Dielectric" "X5R")
    (property "License" "Apache-2.0")
    (property "MPN" "GRM155R61H104KE14D")
    (property "Manufacturer" "Murata")
    (property "Public" "False")
    (property "Sheetfile" "channel1.kicad_sch")
    (property "Sheetname" "Channel 1")
    (property "Val" "100n")
    (property "Voltage" "50V")
    (property "ki_description" "SMD Multilayer Ceramic Capacitor, 0.1 µF, 50 V, 0402 [1005 Metric], ± 10%, X5R, GRM Series")
    (property "ki_keywords" "0402, SMT, CAPACITOR, PASSIVE, CERAMIC, MLCC")
    (attr smd)
    (fp_text reference "C15" (at -3.2 0.3 90) (layer "F.SilkS")
        (effects (font (size 0.65 0.65) (thickness 0.13)) (justify left bottom))
    )
    (fp_text value "C_100n_0402" (at 0 1.4 90) (layer "F.Fab")
        (effects (font (size 0.65 0.65) (thickness 0.13)) (justify left bottom))
    )
    (fp_text user "License: Apache-2.0" (at -0.932 5.17 90) (layer "F.Fab") hide
        (effects (font (size 0.7 0.7) (thickness 0.15)) (justify left bottom))
    )
    (fp_text user "Author: Antmicro" (at -0.932 4.17 90) (layer "F.Fab") hide
        (effects (font (size 0.7 0.7) (thickness 0.15)) (justify left bottom))
    )
    (fp_text user "${REFERENCE}" (at -0.932 3.168 90) (layer "F.Fab") hide
        (effects (font (size 0.7 0.7) (thickness 0.15)) (justify left bottom))
    )
    (fp_rect (start -0.925 -0.47) (end 0.925 0.47)
      (stroke (width 0.05) (type default)) (fill none) (layer "F.CrtYd"))
    (fp_line (start -0.494 -0.25) (end 0.504 -0.25)
      (stroke (width 0.15) (type solid)) (layer "F.Fab"))
    (fp_line (start -0.494 0.248) (end -0.494 -0.25)
      (stroke (width 0.15) (type solid)) (layer "F.Fab"))
    (fp_line (start 0.504 -0.25) (end 0.504 0.248)
      (stroke (width 0.15) (type solid)) (layer "F.Fab"))
    (fp_line (start 0.504 0.248) (end -0.494 0.248)
      (stroke (width 0.15) (type solid)) (layer "F.Fab"))
    (pad "1" smd roundrect (at -0.48 0 90) (size 0.59 0.64) (layers "F.Cu" "F.Paste" "F.Mask") (roundrect_rratio 0.25)
      (net 2 "GND") (pintype "passive"))
    (pad "2" smd roundrect (at 0.48 0 90) (size 0.59 0.64) (layers "F.Cu" "F.Paste" "F.Mask") (roundrect_rratio 0.25)
      (net 10 "Net-(Y1-EN)") (pintype "passive"))
  )
	(footprint "antmicro-footprints:R_0402_1005Metric" (layer "F.Cu")
    (at 139.26 105.79 180)
    (descr "Resistor SMD 0402")
    (tags "resistor SMD 0402")
    (property "Author" "Antmicro")
    (property "License" "Apache-2.0")
    (property "MPN" "CR0402-FX-2001GLF")
    (property "Manufacturer" "Bourns")
    (property "Public" "False")
    (property "Sheetfile" "channel1.kicad_sch")
    (property "Sheetname" "Channel 1")
    (property "Tolerance" "1%")
    (property "Val" "2k")
    (property "ki_description" "SMD Chip Resistor, 2 kohm, ± 1%, 62.5 mW, 0402 [1005 Metric], Thick Film, General Purpose")
    (property "ki_keywords" "0402, SMT, RESISTOR, PASSIVE")
    (attr smd)
    (fp_text reference "R4" (at 2.33 -0.39 180) (layer "F.SilkS")
        (effects (font (size 0.65 0.65) (thickness 0.13)) (justify left bottom))
    )
    (fp_text value "R_2k_0402" (at 0 1.4 180) (layer "F.Fab")
        (effects (font (size 0.65 0.65) (thickness 0.13)) (justify left bottom))
    )
    (fp_text user "Author: Antmicro" (at -0.95 4.169 180) (layer "F.Fab") hide
        (effects (font (size 0.7 0.7) (thickness 0.15)) (justify left bottom))
    )
    (fp_text user "${REFERENCE}" (at -0.95 3.168 180) (layer "F.Fab") hide
        (effects (font (size 0.7 0.7) (thickness 0.15)) (justify left bottom))
    )
    (fp_text user "License: Apache-2.0" (at -0.95 5.169 180) (layer "F.Fab") hide
        (effects (font (size 0.7 0.7) (thickness 0.15)) (justify left bottom))
    )
    (fp_rect (start -0.925 -0.47) (end 0.925 0.47)
      (stroke (width 0.05) (type default)) (fill none) (layer "F.CrtYd"))
    (fp_rect (start -0.5 -0.25) (end 0.5 0.25)
      (stroke (width 0.15) (type solid)) (fill none) (layer "F.Fab"))
    (pad "1" smd roundrect (at -0.48 0 180) (size 0.59 0.64) (layers "F.Cu" "F.Paste" "F.Mask") (roundrect_rratio 0.25)
      (net 113 "Net-(U1B-REXT)") (pintype "passive"))
    (pad "2" smd roundrect (at 0.48 0 180) (size 0.59 0.64) (layers "F.Cu" "F.Paste" "F.Mask") (roundrect_rratio 0.25)
      (net 100 "/Channel 1/CH1_AVDD33") (pintype "passive"))
  )
	(footprint "antmicro-footprints:R_0603_1608Metric" (layer "F.Cu")
    (at 144.9 103.35)
    (descr "Resistor SMD 0603")
    (tags "resistor SMD 0603")
    (property "Author" "Antmicro")
    (property "Current" "1A")
    (property "License" "Apache-2.0")
    (property "MPN" "CR0603-J/-000ELF")
    (property "Manufacturer" "Bourns")
    (property "Public" "False")
    (property "Sheetfile" "channel1.kicad_sch")
    (property "Sheetname" "Channel 1")
    (property "Tolerance" "")
    (property "Val" "0R")
    (property "ki_description" "Zero Ohm Resistor, Jumper, 0603 [1608 Metric], Thick Film, 100 mW, 1 A, Surface Mount Device, CR")
    (property "ki_keywords" "0603, SMT, RESISTOR, PASSIVE")
    (attr smd)
    (fp_text reference "R2" (at 1.1 0.4) (layer "F.SilkS")
        (effects (font (size 0.7 0.7) (thickness 0.15)) (justify left bottom))
    )
    (fp_text value "R_0R_0603" (at 0 1.6) (layer "F.Fab")
        (effects (font (size 0.7 0.7) (thickness 0.15)) (justify left bottom))
    )
    (fp_text user "License: Apache-2.0" (at -1.25 5.9) (layer "F.Fab") hide
        (effects (font (size 0.7 0.7) (thickness 0.15)) (justify left bottom))
    )
    (fp_text user "${REFERENCE}" (at -1.25 3.898) (layer "F.Fab") hide
        (effects (font (size 0.7 0.7) (thickness 0.15)) (justify left bottom))
    )
    (fp_text user "Author: Antmicro" (at -1.25 4.9) (layer "F.Fab") hide
        (effects (font (size 0.7 0.7) (thickness 0.15)) (justify left bottom))
    )
    (fp_line (start -0.15 -0.4) (end 0.15 -0.4)
      (stroke (width 0.15) (type solid)) (layer "F.SilkS"))
    (fp_line (start -0.15 0.4) (end 0.15 0.4)
      (stroke (width 0.15) (type solid)) (layer "F.SilkS"))
    (fp_rect (start -1.25 -0.65) (end 1.25 0.65)
      (stroke (width 0.05) (type solid)) (fill none) (layer "F.CrtYd"))
    (fp_rect (start -0.8 -0.4) (end 0.8 0.4)
      (stroke (width 0.15) (type solid)) (fill none) (layer "F.Fab"))
    (pad "1" smd roundrect (at -0.7 0) (size 0.8 1) (layers "F.Cu" "F.Paste" "F.Mask") (roundrect_rratio 0.2)
      (net 86 "/Channel 1/HDMI1_POWER") (pintype "passive"))
    (pad "2" smd roundrect (at 0.7 0) (size 0.8 1) (layers "F.Cu" "F.Paste" "F.Mask") (roundrect_rratio 0.2)
      (net 97 "/Channel 1/HDMI1_HPDI") (pintype "passive"))
  )
	(footprint "antmicro-footprints:R_0402_1005Metric" (layer "F.Cu")
    (at 143.87 104.59)
    (descr "Resistor SMD 0402")
    (tags "resistor SMD 0402")
    (property "Author" "Antmicro")
    (property "License" "Apache-2.0")
    (property "MPN" "CR0402-FX-1002GLF")
    (property "Manufacturer" "Bourns")
    (property "Public" "False")
    (property "Sheetfile" "channel1.kicad_sch")
    (property "Sheetname" "Channel 1")
    (property "Tolerance" "1%")
    (property "Val" "10k")
    (property "ki_description" "SMD Chip Resistor, 10 kohm, ± 1%, 62.5 mW, 0402 [1005 Metric], Thick Film, General Purpose")
    (property "ki_keywords" "0402, SMT, RESISTOR, PASSIVE")
    (attr smd)
    (fp_text reference "R12" (at 0.73 0.16) (layer "F.SilkS")
        (effects (font (size 0.65 0.65) (thickness 0.13)) (justify left bottom))
    )
    (fp_text value "R_10k_0402" (at 0 1.4) (layer "F.Fab")
        (effects (font (size 0.65 0.65) (thickness 0.13)) (justify left bottom))
    )
    (fp_text user "Author: Antmicro" (at -0.95 4.169) (layer "F.Fab") hide
        (effects (font (size 0.7 0.7) (thickness 0.15)) (justify left bottom))
    )
    (fp_text user "${REFERENCE}" (at -0.95 3.168) (layer "F.Fab") hide
        (effects (font (size 0.7 0.7) (thickness 0.15)) (justify left bottom))
    )
    (fp_text user "License: Apache-2.0" (at -0.95 5.169) (layer "F.Fab") hide
        (effects (font (size 0.7 0.7) (thickness 0.15)) (justify left bottom))
    )
    (fp_rect (start -0.925 -0.47) (end 0.925 0.47)
      (stroke (width 0.05) (type default)) (fill none) (layer "F.CrtYd"))
    (fp_rect (start -0.5 -0.25) (end 0.5 0.25)
      (stroke (width 0.15) (type solid)) (fill none) (layer "F.Fab"))
    (pad "1" smd roundrect (at -0.48 0) (size 0.59 0.64) (layers "F.Cu" "F.Paste" "F.Mask") (roundrect_rratio 0.25)
      (net 85 "/Channel 1/HDMI1_DDC_SDA") (pintype "passive"))
    (pad "2" smd roundrect (at 0.48 0) (size 0.59 0.64) (layers "F.Cu" "F.Paste" "F.Mask") (roundrect_rratio 0.25)
      (net 14 "+5V") (pintype "passive"))
  )
	(footprint "antmicro-footprints:C_0402_1005Metric" (layer "F.Cu")
    (at 139.64 108.15)
    (descr "Capacitor SMD 0402")
    (tags "capacitor SMD 0402")
    (property "Author" "Antmicro")
    (property "Dielectric" "")
    (property "License" "Apache-2.0")
    (property "MPN" "0402B471K250CT")
    (property "Manufacturer" "Walsin")
    (property "Public" "False")
    (property "Sheetfile" "channel1.kicad_sch")
    (property "Sheetname" "Channel 1")
    (property "Val" "470p")
    (property "Voltage" "")
    (property "ki_description" "SMD Multilayer Ceramic Capacitor, General Purpose, 470 pF, 25 V, 0402 [1005 Metric], ± 10%, X7R")
    (property "ki_keywords" "0402, SMT, CAPACITOR, PASSIVE, MLCC")
    (attr smd)
    (fp_text reference "C5" (at 0.78 0.39) (layer "F.SilkS")
        (effects (font (size 0.65 0.65) (thickness 0.13)) (justify left bottom))
    )
    (fp_text value "C_470p_0402" (at 0 1.4) (layer "F.Fab")
        (effects (font (size 0.65 0.65) (thickness 0.13)) (justify left bottom))
    )
    (fp_text user "License: Apache-2.0" (at -0.932 5.17) (layer "F.Fab") hide
        (effects (font (size 0.7 0.7) (thickness 0.15)) (justify left bottom))
    )
    (fp_text user "${REFERENCE}" (at -0.932 3.168) (layer "F.Fab") hide
        (effects (font (size 0.7 0.7) (thickness 0.15)) (justify left bottom))
    )
    (fp_text user "Author: Antmicro" (at -0.932 4.17) (layer "F.Fab") hide
        (effects (font (size 0.7 0.7) (thickness 0.15)) (justify left bottom))
    )
    (fp_rect (start -0.925 -0.47) (end 0.925 0.47)
      (stroke (width 0.05) (type default)) (fill none) (layer "F.CrtYd"))
    (fp_line (start -0.494 -0.25) (end 0.504 -0.25)
      (stroke (width 0.15) (type solid)) (layer "F.Fab"))
    (fp_line (start -0.494 0.248) (end -0.494 -0.25)
      (stroke (width 0.15) (type solid)) (layer "F.Fab"))
    (fp_line (start 0.504 -0.25) (end 0.504 0.248)
      (stroke (width 0.15) (type solid)) (layer "F.Fab"))
    (fp_line (start 0.504 0.248) (end -0.494 0.248)
      (stroke (width 0.15) (type solid)) (layer "F.Fab"))
    (pad "1" smd roundrect (at -0.48 0) (size 0.59 0.64) (layers "F.Cu" "F.Paste" "F.Mask") (roundrect_rratio 0.25)
      (net 6 "Net-(C5-Pad1)") (pintype "passive"))
    (pad "2" smd roundrect (at 0.48 0) (size 0.59 0.64) (layers "F.Cu" "F.Paste" "F.Mask") (roundrect_rratio 0.25)
      (net 2 "GND") (pintype "passive"))
  )
	(footprint "antmicro-footprints:C_0402_1005Metric" (layer "F.Cu")
    (at 155.01 108.45 180)
    (descr "Capacitor SMD 0402")
    (tags "capacitor SMD 0402")
    (property "Author" "Antmicro")
    (property "Dielectric" "")
    (property "License" "Apache-2.0")
    (property "MPN" "0402B471K250CT")
    (property "Manufacturer" "Walsin")
    (property "Public" "False")
    (property "Sheetfile" "channel2.kicad_sch")
    (property "Sheetname" "Channel 2")
    (property "Val" "470p")
    (property "Voltage" "")
    (property "ki_description" "SMD Multilayer Ceramic Capacitor, General Purpose, 470 pF, 25 V, 0402 [1005 Metric], ± 10%, X7R")
    (property "ki_keywords" "0402, SMT, CAPACITOR, PASSIVE, MLCC")
    (attr smd)
    (fp_text reference "C50" (at -0.62 -7.52) (layer "F.SilkS")
        (effects (font (size 0.65 0.65) (thickness 0.13)) (justify right bottom))
    )
    (fp_text value "C_470p_0402" (at 0 1.4) (layer "F.Fab")
        (effects (font (size 0.65 0.65) (thickness 0.13)) (justify right bottom))
    )
    (fp_text user "${REFERENCE}" (at -0.932 3.168) (layer "F.Fab") hide
        (effects (font (size 0.7 0.7) (thickness 0.15)) (justify right bottom))
    )
    (fp_text user "License: Apache-2.0" (at -0.932 5.17) (layer "F.Fab") hide
        (effects (font (size 0.7 0.7) (thickness 0.15)) (justify right bottom))
    )
    (fp_text user "Author: Antmicro" (at -0.932 4.17) (layer "F.Fab") hide
        (effects (font (size 0.7 0.7) (thickness 0.15)) (justify right bottom))
    )
    (fp_rect (start -0.925 -0.47) (end 0.925 0.47)
      (stroke (width 0.05) (type default)) (fill none) (layer "F.CrtYd"))
    (fp_line (start -0.494 -0.25) (end 0.504 -0.25)
      (stroke (width 0.15) (type solid)) (layer "F.Fab"))
    (fp_line (start -0.494 0.248) (end -0.494 -0.25)
      (stroke (width 0.15) (type solid)) (layer "F.Fab"))
    (fp_line (start 0.504 -0.25) (end 0.504 0.248)
      (stroke (width 0.15) (type solid)) (layer "F.Fab"))
    (fp_line (start 0.504 0.248) (end -0.494 0.248)
      (stroke (width 0.15) (type solid)) (layer "F.Fab"))
    (pad "1" smd roundrect (at -0.48 0 180) (size 0.59 0.64) (layers "F.Cu" "F.Paste" "F.Mask") (roundrect_rratio 0.25)
      (net 33 "Net-(U4B-VDDC1)") (pintype "passive"))
    (pad "2" smd roundrect (at 0.48 0 180) (size 0.59 0.64) (layers "F.Cu" "F.Paste" "F.Mask") (roundrect_rratio 0.25)
      (net 2 "GND") (pintype "passive"))
  )
	(footprint "antmicro-footprints:C_0402_1005Metric" (layer "F.Cu")
    (at 155.07 112.45)
    (descr "Capacitor SMD 0402")
    (tags "capacitor SMD 0402")
    (property "Author" "Antmicro")
    (property "Dielectric" "C0G")
    (property "License" "Apache-2.0")
    (property "MPN" "C0402C470J5GACTU")
    (property "Manufacturer" "KEMET")
    (property "Public" "False")
    (property "Sheetfile" "channel2.kicad_sch")
    (property "Sheetname" "Channel 2")
    (property "Val" "47p")
    (property "Voltage" "")
    (property "ki_description" "SMD Multilayer Ceramic Capacitor, 47 pF, 50 V, 0402 [1005 Metric], ± 5%, C0G / NP0, C Series KEMET")
    (property "ki_keywords" "0402, SMT, CAPACITOR, PASSIVE, CERAMIC, MLCC")
    (attr smd)
    (fp_text reference "C46" (at -1.56 7.52) (layer "F.SilkS")
        (effects (font (size 0.65 0.65) (thickness 0.13)) (justify left bottom))
    )
    (fp_text value "C_47p_0402" (at 0 1.4) (layer "F.Fab")
        (effects (font (size 0.65 0.65) (thickness 0.13)) (justify left bottom))
    )
    (fp_text user "Author: Antmicro" (at -0.932 4.17) (layer "F.Fab") hide
        (effects (font (size 0.7 0.7) (thickness 0.15)) (justify left bottom))
    )
    (fp_text user "License: Apache-2.0" (at -0.932 5.17) (layer "F.Fab") hide
        (effects (font (size 0.7 0.7) (thickness 0.15)) (justify left bottom))
    )
    (fp_text user "${REFERENCE}" (at -0.932 3.168) (layer "F.Fab") hide
        (effects (font (size 0.7 0.7) (thickness 0.15)) (justify left bottom))
    )
    (fp_rect (start -0.925 -0.47) (end 0.925 0.47)
      (stroke (width 0.05) (type default)) (fill none) (layer "F.CrtYd"))
    (fp_line (start -0.494 -0.25) (end 0.504 -0.25)
      (stroke (width 0.15) (type solid)) (layer "F.Fab"))
    (fp_line (start -0.494 0.248) (end -0.494 -0.25)
      (stroke (width 0.15) (type solid)) (layer "F.Fab"))
    (fp_line (start 0.504 -0.25) (end 0.504 0.248)
      (stroke (width 0.15) (type solid)) (layer "F.Fab"))
    (fp_line (start 0.504 0.248) (end -0.494 0.248)
      (stroke (width 0.15) (type solid)) (layer "F.Fab"))
    (pad "1" smd roundrect (at -0.48 0) (size 0.59 0.64) (layers "F.Cu" "F.Paste" "F.Mask") (roundrect_rratio 0.25)
      (net 2 "GND") (pintype "passive"))
    (pad "2" smd roundrect (at 0.48 0) (size 0.59 0.64) (layers "F.Cu" "F.Paste" "F.Mask") (roundrect_rratio 0.25)
      (net 27 "/Channel 2/CH2_REFCLK") (pintype "passive"))
  )
)
